(kicad_pcb
	(version 20260206)
	(generator "pcbnew")
	(generator_version "10.0")
	(general
		(thickness 1.6)
		(legacy_teardrops no)
	)
	(paper "A4")
	(title_block
		(title "v1-chassis-manager — T6M_CM_d_v01_1031_1645.brd")
		(comment 1 "Open CloudServer (Microsoft) / footprints 1453-1459 of 2512")
	)
	(layers
		(0 "F.Cu" signal "TOP")
		(4 "In1.Cu" signal "GND1")
		(6 "In2.Cu" signal "IN1")
		(8 "In3.Cu" signal "VCC1")
		(10 "In4.Cu" signal "VCC2")
		(12 "In5.Cu" signal "GND2")
		(14 "In6.Cu" signal "IN2")
		(16 "In7.Cu" signal "IN3")
		(18 "In8.Cu" signal "GND3")
		(2 "B.Cu" signal "BOTTOM")
		(9 "F.Adhes" user "F.Adhesive")
		(11 "B.Adhes" user "B.Adhesive")
		(13 "F.Paste" user "Package Geometry/Pastemask Top")
		(15 "B.Paste" user "Package Geometry/Pastemask Bottom")
		(5 "F.SilkS" user "Ref Des/Silkscreen Top")
		(7 "B.SilkS" user "Ref Des/Silkscreen Bottom")
		(1 "F.Mask" user "Board Geometry/Soldermask Top")
		(3 "B.Mask" user "Board Geometry/Soldermask Bottom")
		(17 "Dwgs.User" user "User.Drawings")
		(19 "Cmts.User" user "User.Comments")
		(21 "Eco1.User" user "User.Eco1")
		(23 "Eco2.User" user "User.Eco2")
		(25 "Edge.Cuts" user "Board Geometry/Outline")
		(27 "Margin" user)
		(31 "F.CrtYd" user "Package Geometry/Place Bound Top")
		(29 "B.CrtYd" user "Package Geometry/Place Bound Bottom")
		(35 "F.Fab" user "Ref Des/Assembly Top")
		(33 "B.Fab" user "Ref Des/Assembly Bottom")
	)
	(footprint ""
		(layer "F.Cu")
		(at 33.33623 -102.214934 -90)
		(property "Reference" "U120"
			(at -3.62839 4.09194 0)
			(unlocked yes)
			(layer "F.SilkS")
			(effects
				(font
					(size 0.7874 0.5842)
					(thickness 0.1524)
				)
				(justify left)
			)
		)
		(property "Value" ""
			(at 0 0 270)
			(layer "F.Fab")
			(effects
				(font
					(size 1.27 1.27)
				)
			)
		)
		(duplicate_pad_numbers_are_jumpers no)
		(fp_line
			(start -2.525014 3.075178)
			(end -2.320798 3.075178)
			(stroke
				(width 0.1524)
				(type default)
			)
			(layer "F.SilkS")
		)
		(fp_line
			(start -2.525014 3.075178)
			(end -2.525014 0.025146)
			(stroke
				(width 0.1524)
				(type default)
			)
			(layer "F.SilkS")
		)
		(fp_line
			(start 0.320802 3.075178)
			(end 0.525018 3.075178)
			(stroke
				(width 0.1524)
				(type default)
			)
			(layer "F.SilkS")
		)
		(fp_line
			(start 0.525018 3.075178)
			(end 0.525018 2.489962)
			(stroke
				(width 0.1524)
				(type default)
			)
			(layer "F.SilkS")
		)
		(fp_line
			(start 0.525018 3.075178)
			(end 0.525018 0.025146)
			(stroke
				(width 0.1524)
				(type default)
			)
			(layer "F.SilkS")
		)
		(fp_line
			(start -2.525014 2.540762)
			(end -2.525014 3.075178)
			(stroke
				(width 0.1524)
				(type default)
			)
			(layer "F.SilkS")
		)
		(fp_line
			(start 0.525018 0.686562)
			(end 0.525018 0.025146)
			(stroke
				(width 0.1524)
				(type default)
			)
			(layer "F.SilkS")
		)
		(fp_line
			(start -2.525014 0.025146)
			(end -2.525014 0.661162)
			(stroke
				(width 0.1524)
				(type default)
			)
			(layer "F.SilkS")
		)
		(fp_line
			(start -2.320798 0.025146)
			(end -2.525014 0.025146)
			(stroke
				(width 0.1524)
				(type default)
			)
			(layer "F.SilkS")
		)
		(fp_line
			(start 0.525018 0.025146)
			(end 0.320802 0.025146)
			(stroke
				(width 0.1524)
				(type default)
			)
			(layer "F.SilkS")
		)
		(fp_poly
			(pts
				(xy 0.55245 -0.45593) (xy 1.452626 -0.155956) (xy 1.452626 -0.755904)
			)
			(stroke
				(width 0)
				(type default)
			)
			(fill yes)
			(layer "F.SilkS")
		)
		(fp_poly
			(pts
				(xy 0.525018 0.025146) (xy 0.244602 0.025146) (xy 0.244602 -0.532638) (xy -2.244598 -0.532638) (xy -2.244598 0.025146)
				(xy -2.525014 0.025146) (xy -2.525014 3.075178) (xy -2.244598 3.075178) (xy -2.244598 3.632962)
				(xy 0.244602 3.632962) (xy 0.244602 3.075178) (xy 0.525018 3.075178)
			)
			(stroke
				(width 0)
				(type default)
			)
			(fill no)
			(layer "F.CrtYd")
		)
		(fp_line
			(start -2.525014 3.075178)
			(end -2.525014 0.025146)
			(stroke
				(width 0.1)
				(type default)
			)
			(layer "F.Fab")
		)
		(fp_line
			(start 0.525018 3.075178)
			(end -2.525014 3.075178)
			(stroke
				(width 0.1)
				(type default)
			)
			(layer "F.Fab")
		)
		(fp_line
			(start -2.525014 0.025146)
			(end 0.525018 0.025146)
			(stroke
				(width 0.1)
				(type default)
			)
			(layer "F.Fab")
		)
		(fp_line
			(start 0.525018 0.025146)
			(end 0.525018 3.075178)
			(stroke
				(width 0.1)
				(type default)
			)
			(layer "F.Fab")
		)
		(fp_poly
			(pts
				(xy 0 -0.519938) (xy 0.302514 -1.427734) (xy -0.302514 -1.427734)
			)
			(stroke
				(width 0)
				(type default)
			)
			(fill yes)
			(layer "F.Fab")
		)
		(fp_text user "10"
			(at 1.107948 3.746246 0)
			(unlocked yes)
			(layer "F.SilkS")
			(effects
				(font
					(size 0.635 0.4064)
					(thickness 0.1524)
				)
				(justify left)
			)
		)
		(fp_text user "6"
			(at -2.678684 3.617468 0)
			(unlocked yes)
			(layer "F.SilkS")
			(effects
				(font
					(size 0.635 0.4064)
					(thickness 0.1524)
				)
				(justify left)
			)
		)
		(fp_text user "1"
			(at 1.2192 0.331724 0)
			(unlocked yes)
			(layer "F.SilkS")
			(effects
				(font
					(size 0.635 0.4064)
					(thickness 0.1524)
				)
				(justify left)
			)
		)
		(fp_text user "5"
			(at -2.660142 -0.187452 0)
			(unlocked yes)
			(layer "F.SilkS")
			(effects
				(font
					(size 0.635 0.4064)
					(thickness 0.1524)
				)
				(justify left)
			)
		)
		(fp_text user "6"
			(at -2.155698 3.725672 90)
			(unlocked yes)
			(layer "F.Fab")
			(effects
				(font
					(size 0.7874 0.5842)
					(thickness 0.000001)
				)
				(justify left)
			)
		)
		(fp_text user "10"
			(at 1.565402 3.700272 90)
			(unlocked yes)
			(layer "F.Fab")
			(effects
				(font
					(size 0.7874 0.5842)
					(thickness 0.000001)
				)
				(justify left)
			)
		)
		(fp_text user "5"
			(at -2.155698 -0.695706 90)
			(unlocked yes)
			(layer "F.Fab")
			(effects
				(font
					(size 0.7874 0.5842)
					(thickness 0.000001)
				)
				(justify left)
			)
		)
		(fp_text user "1"
			(at 0.790702 -0.695706 90)
			(unlocked yes)
			(layer "F.Fab")
			(effects
				(font
					(size 0.7874 0.5842)
					(thickness 0.000001)
				)
				(justify left)
			)
		)
		(pad "1" smd rect
			(at 0 0 90)
			(size 0.2794 0.9144)
			(layers "F.Cu" "F.Mask" "F.Paste")
			(net "P1V5_SUS_NODE1")
		)
		(pad "2" smd rect
			(at -0.499872 0 90)
			(size 0.2794 0.9144)
			(layers "F.Cu" "F.Mask" "F.Paste")
			(net "P1V5_SUS_NODE1")
		)
		(pad "3" smd rect
			(at -0.999998 0 90)
			(size 0.2794 0.9144)
			(layers "F.Cu" "F.Mask" "F.Paste")
			(net "P1V5_SUS_NODE1")
		)
		(pad "4" smd rect
			(at -1.500124 0 90)
			(size 0.2794 0.9144)
			(layers "F.Cu" "F.Mask" "F.Paste")
			(net "P1V5_SUS_NODE1_ADJ")
		)
		(pad "5" smd rect
			(at -1.999996 0 270)
			(size 0.2794 0.9144)
			(layers "F.Cu" "F.Mask" "F.Paste")
			(net "PWRGD_NODE1_P1V5_SUS_PG")
		)
		(pad "6" smd rect
			(at -1.999996 3.100324 270)
			(size 0.2794 0.9144)
			(layers "F.Cu" "F.Mask" "F.Paste")
			(net "FM_CPLD_NODE1_P1V5_SUS_EN")
		)
		(pad "7" smd rect
			(at -1.500124 3.100324 90)
			(size 0.2794 0.9144)
			(layers "F.Cu" "F.Mask" "F.Paste")
			(net "P1V8_STB_NODE1")
		)
		(pad "8" smd rect
			(at -0.999998 3.100324 90)
			(size 0.2794 0.9144)
			(layers "F.Cu" "F.Mask" "F.Paste")
			(net "P1V8_STB_NODE1")
		)
		(pad "9" smd rect
			(at -0.499872 3.100324 90)
			(size 0.2794 0.9144)
			(layers "F.Cu" "F.Mask" "F.Paste")
			(net "P1V8_STB_NODE1")
		)
		(pad "10" smd rect
			(at 0 3.100324 90)
			(size 0.2794 0.9144)
			(layers "F.Cu" "F.Mask" "F.Paste")
			(net "P5V_STB_NODE1")
		)
		(pad "TH" smd rect
			(at -0.999998 1.550162 180)
			(size 1.7526 2.667)
			(layers "F.Cu" "F.Mask" "F.Paste")
			(net "GND")
		)
		(zone
			(layer "F.Cu")
			(hatch none 0.5)
			(connect_pads
				(clearance 0)
			)
			(min_thickness 0.25)
			(keepout
				(tracks allowed)
				(vias not_allowed)
				(pads allowed)
				(copperpour not_allowed)
				(footprints allowed)
			)
			(placement
				(enabled no)
				(sheetname "")
			)
			(fill
				(thermal_gap 0.5)
				(thermal_bridge_width 0.5)
				(island_removal_mode 0)
			)
			(polygon
				(pts
					(xy 32.80283 -101.681534) (xy 32.80283 -104.729534) (xy 30.77083 -104.729534) (xy 30.77083 -101.681534)
					(xy 32.70123 -101.681534) (xy 32.70123 -101.808534) (xy 30.84703 -101.808534) (xy 30.84703 -104.627934)
					(xy 32.72663 -104.627934) (xy 32.72663 -101.681534)
				)
			)
		)
	)
	(footprint ""
		(layer "F.Cu")
		(at 138.66876 -108.370624 90)
		(property "Reference" "R22"
			(at -6.585204 0.466852 90)
			(unlocked yes)
			(layer "F.SilkS")
			(effects
				(font
					(size 0.7874 0.5842)
					(thickness 0.1524)
				)
				(justify left)
			)
		)
		(property "Value" ""
			(at 0 0 90)
			(layer "F.Fab")
			(effects
				(font
					(size 1.27 1.27)
				)
			)
		)
		(duplicate_pad_numbers_are_jumpers no)
		(fp_line
			(start 0.7874 -0.4064)
			(end 0.7874 0.4064)
			(stroke
				(width 0.1524)
				(type default)
			)
			(layer "F.SilkS")
		)
		(fp_line
			(start -0.7874 -0.4064)
			(end 0.7874 -0.4064)
			(stroke
				(width 0.1524)
				(type default)
			)
			(layer "F.SilkS")
		)
		(fp_line
			(start 0.7874 0.4064)
			(end -0.7874 0.4064)
			(stroke
				(width 0.1524)
				(type default)
			)
			(layer "F.SilkS")
		)
		(fp_line
			(start -0.7874 0.4064)
			(end -0.7874 -0.4064)
			(stroke
				(width 0.1524)
				(type default)
			)
			(layer "F.SilkS")
		)
		(fp_poly
			(pts
				(xy -0.508 0.2794) (xy -0.508 0.2286) (xy -0.635 0.2286) (xy -0.635 -0.254) (xy -0.5334 -0.254)
				(xy -0.5334 -0.2794) (xy 0.5334 -0.2794) (xy 0.5334 -0.254) (xy 0.635 -0.254) (xy 0.635 0.254) (xy 0.5334 0.254)
				(xy 0.5334 0.2794)
			)
			(stroke
				(width 0)
				(type default)
			)
			(fill no)
			(layer "F.CrtYd")
		)
		(pad "1" smd rect
			(at 0.40005 0 90)
			(size 0.4572 0.508)
			(layers "F.Cu" "F.Mask" "F.Paste")
			(net "CLK_14M_CPU_NODE1_R")
		)
		(pad "2" smd rect
			(at -0.40005 0 90)
			(size 0.4572 0.508)
			(layers "F.Cu" "F.Mask" "F.Paste")
			(net "P3V3_CLK_NODE1")
		)
	)
	(footprint ""
		(layer "F.Cu")
		(at 111.74476 -185.205624 -90)
		(property "Reference" "R884"
			(at -4.768088 -0.724408 90)
			(unlocked yes)
			(layer "F.SilkS")
			(effects
				(font
					(size 0.7874 0.5842)
					(thickness 0.1524)
				)
				(justify left)
			)
		)
		(property "Value" ""
			(at 0 0 270)
			(layer "F.Fab")
			(effects
				(font
					(size 1.27 1.27)
				)
			)
		)
		(duplicate_pad_numbers_are_jumpers no)
		(fp_line
			(start -0.7874 0.4064)
			(end -0.7874 -0.4064)
			(stroke
				(width 0.1524)
				(type default)
			)
			(layer "F.SilkS")
		)
		(fp_line
			(start 0.7874 0.4064)
			(end -0.7874 0.4064)
			(stroke
				(width 0.1524)
				(type default)
			)
			(layer "F.SilkS")
		)
		(fp_line
			(start -0.7874 -0.4064)
			(end 0.7874 -0.4064)
			(stroke
				(width 0.1524)
				(type default)
			)
			(layer "F.SilkS")
		)
		(fp_line
			(start 0.7874 -0.4064)
			(end 0.7874 0.4064)
			(stroke
				(width 0.1524)
				(type default)
			)
			(layer "F.SilkS")
		)
		(fp_poly
			(pts
				(xy -0.508 0.2794) (xy -0.508 0.2286) (xy -0.635 0.2286) (xy -0.635 -0.254) (xy -0.5334 -0.254)
				(xy -0.5334 -0.2794) (xy 0.5334 -0.2794) (xy 0.5334 -0.254) (xy 0.635 -0.254) (xy 0.635 0.254) (xy 0.5334 0.254)
				(xy 0.5334 0.2794)
			)
			(stroke
				(width 0)
				(type default)
			)
			(fill no)
			(layer "F.CrtYd")
		)
		(pad "1" smd rect
			(at 0.40005 0 270)
			(size 0.4572 0.508)
			(layers "F.Cu" "F.Mask" "F.Paste")
			(net "T6_NODE1_EN")
		)
		(pad "2" smd rect
			(at -0.40005 0 270)
			(size 0.4572 0.508)
			(layers "F.Cu" "F.Mask" "F.Paste")
			(net "T6_NODE1_EN_R")
		)
	)
	(footprint ""
		(layer "F.Cu")
		(at 52.81676 -182.246524 90)
		(property "Reference" "C600"
			(at -133.313932 -3.637788 90)
			(unlocked yes)
			(layer "F.SilkS")
			(effects
				(font
					(size 0.7874 0.5842)
					(thickness 0.1524)
				)
				(justify left)
			)
		)
		(property "Value" ""
			(at 0 0 90)
			(layer "F.Fab")
			(effects
				(font
					(size 1.27 1.27)
				)
			)
		)
		(duplicate_pad_numbers_are_jumpers no)
		(fp_line
			(start 0.7874 -0.4064)
			(end 0.7874 0.4064)
			(stroke
				(width 0.1524)
				(type default)
			)
			(layer "F.SilkS")
		)
		(fp_line
			(start -0.7874 -0.4064)
			(end 0.7874 -0.4064)
			(stroke
				(width 0.1524)
				(type default)
			)
			(layer "F.SilkS")
		)
		(fp_line
			(start 0 0.381)
			(end 0 -0.381)
			(stroke
				(width 0.1524)
				(type default)
			)
			(layer "F.SilkS")
		)
		(fp_line
			(start 0.7874 0.4064)
			(end -0.7874 0.4064)
			(stroke
				(width 0.1524)
				(type default)
			)
			(layer "F.SilkS")
		)
		(fp_line
			(start -0.7874 0.4064)
			(end -0.7874 -0.4064)
			(stroke
				(width 0.1524)
				(type default)
			)
			(layer "F.SilkS")
		)
		(fp_poly
			(pts
				(xy -0.5334 0.254) (xy -0.635 0.254) (xy -0.635 0.2286) (xy -0.635 -0.254) (xy -0.5334 -0.254) (xy -0.5334 -0.2794)
				(xy 0.5334 -0.2794) (xy 0.5334 -0.254) (xy 0.635 -0.254) (xy 0.635 0.254) (xy 0.5334 0.254) (xy 0.5334 0.2794)
				(xy -0.508 0.2794) (xy -0.5334 0.2794)
			)
			(stroke
				(width 0)
				(type default)
			)
			(fill no)
			(layer "F.CrtYd")
		)
		(pad "1" smd rect
			(at 0.40005 0 90)
			(size 0.4572 0.508)
			(layers "F.Cu" "F.Mask" "F.Paste")
			(net "PSU1_AC_OK")
		)
		(pad "2" smd rect
			(at -0.40005 0 90)
			(size 0.4572 0.508)
			(layers "F.Cu" "F.Mask" "F.Paste")
			(net "GND")
		)
	)
	(footprint ""
		(layer "F.Cu")
		(at 152.67051 -149.073362 180)
		(property "Reference" "R588"
			(at 1.33858 3.613912 0)
			(unlocked yes)
			(layer "F.SilkS")
			(effects
				(font
					(size 0.635 0.4064)
					(thickness 0.1524)
				)
				(justify left)
			)
		)
		(property "Value" ""
			(at 0 0 180)
			(layer "F.Fab")
			(effects
				(font
					(size 1.27 1.27)
				)
			)
		)
		(duplicate_pad_numbers_are_jumpers no)
		(fp_line
			(start 0.7874 0.4064)
			(end -0.7874 0.4064)
			(stroke
				(width 0.1524)
				(type default)
			)
			(layer "F.SilkS")
		)
		(fp_line
			(start 0.7874 -0.4064)
			(end 0.7874 0.4064)
			(stroke
				(width 0.1524)
				(type default)
			)
			(layer "F.SilkS")
		)
		(fp_line
			(start -0.7874 0.4064)
			(end -0.7874 -0.4064)
			(stroke
				(width 0.1524)
				(type default)
			)
			(layer "F.SilkS")
		)
		(fp_line
			(start -0.7874 -0.4064)
			(end 0.7874 -0.4064)
			(stroke
				(width 0.1524)
				(type default)
			)
			(layer "F.SilkS")
		)
		(fp_poly
			(pts
				(xy -0.508 0.2794) (xy -0.508 0.2286) (xy -0.635 0.2286) (xy -0.635 -0.254) (xy -0.5334 -0.254)
				(xy -0.5334 -0.2794) (xy 0.5334 -0.2794) (xy 0.5334 -0.254) (xy 0.635 -0.254) (xy 0.635 0.254) (xy 0.5334 0.254)
				(xy 0.5334 0.2794)
			)
			(stroke
				(width 0)
				(type default)
			)
			(fill no)
			(layer "F.CrtYd")
		)
		(pad "1" smd rect
			(at 0.40005 0 180)
			(size 0.4572 0.508)
			(layers "F.Cu" "F.Mask" "F.Paste")
			(net "GND")
		)
		(pad "2" smd rect
			(at -0.40005 0 180)
			(size 0.4572 0.508)
			(layers "F.Cu" "F.Mask" "F.Paste")
			(net "LAN2_TEST_EN")
		)
	)
	(footprint ""
		(layer "F.Cu")
		(at 119.690134 -49.875186 90)
		(property "Reference" "R181"
			(at 1.087628 -0.643128 90)
			(unlocked yes)
			(layer "F.SilkS")
			(effects
				(font
					(size 0.7874 0.5842)
					(thickness 0.1524)
				)
				(justify left)
			)
		)
		(property "Value" ""
			(at 0 0 90)
			(layer "F.Fab")
			(effects
				(font
					(size 1.27 1.27)
				)
			)
		)
		(duplicate_pad_numbers_are_jumpers no)
		(fp_line
			(start 0.7874 -0.4064)
			(end 0.7874 0.4064)
			(stroke
				(width 0.1524)
				(type default)
			)
			(layer "F.SilkS")
		)
		(fp_line
			(start -0.7874 -0.4064)
			(end 0.7874 -0.4064)
			(stroke
				(width 0.1524)
				(type default)
			)
			(layer "F.SilkS")
		)
		(fp_line
			(start 0.7874 0.4064)
			(end -0.7874 0.4064)
			(stroke
				(width 0.1524)
				(type default)
			)
			(layer "F.SilkS")
		)
		(fp_line
			(start -0.7874 0.4064)
			(end -0.7874 -0.4064)
			(stroke
				(width 0.1524)
				(type default)
			)
			(layer "F.SilkS")
		)
		(fp_poly
			(pts
				(xy -0.508 0.2794) (xy -0.508 0.2286) (xy -0.635 0.2286) (xy -0.635 -0.254) (xy -0.5334 -0.254)
				(xy -0.5334 -0.2794) (xy 0.5334 -0.2794) (xy 0.5334 -0.254) (xy 0.635 -0.254) (xy 0.635 0.254) (xy 0.5334 0.254)
				(xy 0.5334 0.2794)
			)
			(stroke
				(width 0)
				(type default)
			)
			(fill no)
			(layer "F.CrtYd")
		)
		(pad "1" smd rect
			(at 0.40005 0 90)
			(size 0.4572 0.508)
			(layers "F.Cu" "F.Mask" "F.Paste")
			(net "LPC_CPU_NODE1_FRAME_L")
		)
		(pad "2" smd rect
			(at -0.40005 0 90)
			(size 0.4572 0.508)
			(layers "F.Cu" "F.Mask" "F.Paste")
			(net "LPC_CPU_NODE1_FRAME_SIO_L")
		)
	)
	(footprint ""
		(layer "F.Cu")
		(at 116.914676 -47.55007 180)
		(property "Reference" "L20"
			(at -0.03556 1.307084 0)
			(unlocked yes)
			(layer "F.SilkS")
			(effects
				(font
					(size 0.7874 0.5842)
					(thickness 0.1524)
				)
			)
		)
		(property "Value" ""
			(at 0 0 180)
			(layer "F.Fab")
			(effects
				(font
					(size 1.27 1.27)
				)
			)
		)
		(duplicate_pad_numbers_are_jumpers no)
		(fp_line
			(start 1.2954 0.635)
			(end -1.2954 0.635)
			(stroke
				(width 0.1524)
				(type default)
			)
			(layer "F.SilkS")
		)
		(fp_line
			(start 1.2954 -0.635)
			(end 1.2954 0.635)
			(stroke
				(width 0.1524)
				(type default)
			)
			(layer "F.SilkS")
		)
		(fp_line
			(start 0.127 -0.5842)
			(end 0.127 0.5842)
			(stroke
				(width 0.1524)
				(type default)
			)
			(layer "F.SilkS")
		)
		(fp_line
			(start -0.127 -0.5842)
			(end -0.127 0.5842)
			(stroke
				(width 0.1524)
				(type default)
			)
			(layer "F.SilkS")
		)
		(fp_line
			(start -1.2954 -0.635)
			(end 1.2954 -0.635)
			(stroke
				(width 0.1524)
				(type default)
			)
			(layer "F.SilkS")
		)
		(fp_line
			(start -1.2954 -0.635)
			(end -1.2954 0.635)
			(stroke
				(width 0.1524)
				(type default)
			)
			(layer "F.SilkS")
		)
		(fp_poly
			(pts
				(xy -0.9144 0.508) (xy -0.9144 0.3556) (xy -1.143 0.3556) (xy -1.143 -0.3556) (xy -0.9144 -0.3556)
				(xy -0.9144 -0.508) (xy 0.9144 -0.508) (xy 0.9144 -0.3556) (xy 1.143 -0.3556) (xy 1.143 0.3556)
				(xy 0.9144 0.3556) (xy 0.9144 0.508)
			)
			(stroke
				(width 0)
				(type default)
			)
			(fill no)
			(layer "F.CrtYd")
		)
		(pad "1" smd rect
			(at 0.7366 0 270)
			(size 0.7112 0.8128)
			(layers "F.Cu" "F.Mask" "F.Paste")
			(net "P3V3_NODE1")
		)
		(pad "2" smd rect
			(at -0.7366 0 270)
			(size 0.7112 0.8128)
			(layers "F.Cu" "F.Mask" "F.Paste")
			(net "N46114787")
		)
	)
)
